# S9S_MB_2U (Grand Teton) — schematic netlist excerpt (pin names and nets, part order shuffled) for the footprints in the layout excerpt that follows; sources: Cadence DE-HDL packaged netlist, KiCad conversion of 03242023_DA0F0TMBIJ0_F0T_Motherboard_J_brd_V01_OCP.brd

R2788  Q_RES  0 5% EMPTY  pkg 0402LF  page 152 : A = USB2_HOST_BMC_B_BUF_DP ; B = USB2_HUB_BUF_SWB_R_DP
C1347  Q_CAP  0.1UF 25V 10% EMPTY  pkg 0402  page 250 : A = MAX11617_VREF ; B = GND

(kicad_pcb
	(version 20260206)
	(generator "pcbnew")
	(generator_version "10.0")
	(general
		(thickness 1.6)
		(legacy_teardrops no)
	)
	(paper "A4")
	(title_block
		(title "03242023_DA0F0TMBIJ0_F0T_Motherboard_J_brd_V01_OCP.brd")
		(comment 1 "Grand Teton / footprints 1061-1062 of 6105")
	)
	(layers
		(0 "F.Cu" signal "TOP")
		(4 "In1.Cu" signal "GND")
		(6 "In2.Cu" signal "IN1")
		(8 "In3.Cu" signal "GND1")
		(10 "In4.Cu" signal "IN2")
		(12 "In5.Cu" signal "GND2")
		(14 "In6.Cu" signal "IN3")
		(16 "In7.Cu" signal "GND3")
		(18 "In8.Cu" signal "VCC")
		(20 "In9.Cu" signal "VCC1")
		(22 "In10.Cu" signal "GND4")
		(24 "In11.Cu" signal "IN4")
		(26 "In12.Cu" signal "GND5")
		(28 "In13.Cu" signal "IN5")
		(30 "In14.Cu" signal "GND6")
		(32 "In15.Cu" signal "IN6")
		(34 "In16.Cu" signal "GND7")
		(2 "B.Cu" signal "BOTTOM")
		(9 "F.Adhes" user "F.Adhesive")
		(11 "B.Adhes" user "B.Adhesive")
		(13 "F.Paste" user "Package Geometry/Pastemask Top")
		(15 "B.Paste" user "Package Geometry/Pastemask Bottom")
		(5 "F.SilkS" user "Ref Des/Silkscreen Top")
		(7 "B.SilkS" user "Ref Des/Silkscreen Bottom")
		(1 "F.Mask" user "Board Geometry/Soldermask Top")
		(3 "B.Mask" user "Board Geometry/Soldermask Bottom")
		(17 "Dwgs.User" user "User.Drawings")
		(19 "Cmts.User" user "User.Comments")
		(21 "Eco1.User" user "User.Eco1")
		(23 "Eco2.User" user "User.Eco2")
		(25 "Edge.Cuts" user "Board Geometry/Outline")
		(27 "Margin" user)
		(31 "F.CrtYd" user "Package Geometry/Place Bound Top")
		(29 "B.CrtYd" user "Package Geometry/Place Bound Bottom")
		(35 "F.Fab" user "Ref Des/Assembly Top")
		(33 "B.Fab" user "Ref Des/Assembly Bottom")
	)
	(footprint ""
		(layer "F.Cu")
		(at 30.094428 -102.761034 180)
		(property "Reference" "C1347"
			(at 0 0 180)
			(layer "F.SilkS")
			(hide yes)
			(effects
				(font
					(size 1.27 1.27)
				)
			)
		)
		(property "Value" ""
			(at 0 0 180)
			(layer "F.Fab")
			(effects
				(font
					(size 1.27 1.27)
				)
			)
		)
		(duplicate_pad_numbers_are_jumpers no)
		(fp_line
			(start 0.7874 0.4064)
			(end -0.7874 0.4064)
			(stroke
				(width 0.1524)
				(type default)
			)
			(layer "F.SilkS")
		)
		(fp_line
			(start 0.7874 -0.4064)
			(end 0.7874 0.4064)
			(stroke
				(width 0.1524)
				(type default)
			)
			(layer "F.SilkS")
		)
		(fp_line
			(start -0.7874 0.4064)
			(end -0.7874 -0.4064)
			(stroke
				(width 0.1524)
				(type default)
			)
			(layer "F.SilkS")
		)
		(fp_line
			(start -0.7874 -0.4064)
			(end 0.7874 -0.4064)
			(stroke
				(width 0.1524)
				(type default)
			)
			(layer "F.SilkS")
		)
		(fp_line
			(start 0.67945 0.3048)
			(end 0.120396 0.3048)
			(stroke
				(width 0.1)
				(type default)
			)
			(layer "F.Fab")
		)
		(fp_line
			(start 0.67945 -0.3048)
			(end 0.67945 0.3048)
			(stroke
				(width 0.1)
				(type default)
			)
			(layer "F.Fab")
		)
		(fp_line
			(start 0.12065 -0.2794)
			(end 0.12065 -0.3048)
			(stroke
				(width 0.1)
				(type default)
			)
			(layer "F.Fab")
		)
		(fp_line
			(start 0.12065 -0.3048)
			(end 0.67945 -0.3048)
			(stroke
				(width 0.1)
				(type default)
			)
			(layer "F.Fab")
		)
		(fp_line
			(start 0.120396 0.3048)
			(end 0.120396 0.2794)
			(stroke
				(width 0.1)
				(type default)
			)
			(layer "F.Fab")
		)
		(fp_line
			(start 0.120396 0.2794)
			(end -0.12065 0.2794)
			(stroke
				(width 0.1)
				(type default)
			)
			(layer "F.Fab")
		)
		(fp_line
			(start -0.12065 0.3048)
			(end -0.67945 0.3048)
			(stroke
				(width 0.1)
				(type default)
			)
			(layer "F.Fab")
		)
		(fp_line
			(start -0.12065 0.2794)
			(end -0.12065 0.3048)
			(stroke
				(width 0.1)
				(type default)
			)
			(layer "F.Fab")
		)
		(fp_line
			(start -0.12065 -0.2794)
			(end 0.12065 -0.2794)
			(stroke
				(width 0.1)
				(type default)
			)
			(layer "F.Fab")
		)
		(fp_line
			(start -0.12065 -0.305054)
			(end -0.12065 -0.2794)
			(stroke
				(width 0.1)
				(type default)
			)
			(layer "F.Fab")
		)
		(fp_line
			(start -0.67945 0.3048)
			(end -0.67945 -0.305054)
			(stroke
				(width 0.1)
				(type default)
			)
			(layer "F.Fab")
		)
		(fp_line
			(start -0.67945 -0.305054)
			(end -0.12065 -0.305054)
			(stroke
				(width 0.1)
				(type default)
			)
			(layer "F.Fab")
		)
		(pad "1" smd circle
			(at -0.40005 0 180)
			(size 0 0)
			(layers "F.Cu" "F.Mask" "F.Paste")
			(net "MAX11617_VREF")
		)
		(pad "2" smd circle
			(at 0.40005 0 180)
			(size 0 0)
			(layers "F.Cu" "F.Mask" "F.Paste")
			(net "GND")
		)
	)
	(footprint ""
		(layer "F.Cu")
		(at 11.421618 -106.28249 -90)
		(property "Reference" "R2788"
			(at 0 0 270)
			(layer "F.SilkS")
			(hide yes)
			(effects
				(font
					(size 1.27 1.27)
				)
			)
		)
		(property "Value" ""
			(at 0 0 270)
			(layer "F.Fab")
			(effects
				(font
					(size 1.27 1.27)
				)
			)
		)
		(duplicate_pad_numbers_are_jumpers no)
		(fp_line
			(start 0.7874 0.4064)
			(end -0.7874 0.4064)
			(stroke
				(width 0.1524)
				(type default)
			)
			(layer "F.SilkS")
		)
		(fp_line
			(start -0.7874 -0.4064)
			(end 0.00889 -0.4064)
			(stroke
				(width 0.1524)
				(type default)
			)
			(layer "F.SilkS")
		)
		(fp_line
			(start 0.7874 -0.4064)
			(end 0.7874 0.4064)
			(stroke
				(width 0.1524)
				(type default)
			)
			(layer "F.SilkS")
		)
		(fp_line
			(start -0.67945 0.3048)
			(end -0.67945 -0.305054)
			(stroke
				(width 0.1)
				(type default)
			)
			(layer "F.Fab")
		)
		(fp_line
			(start -0.12065 0.3048)
			(end -0.67945 0.3048)
			(stroke
				(width 0.1)
				(type default)
			)
			(layer "F.Fab")
		)
		(fp_line
			(start 0.120396 0.3048)
			(end 0.120396 0.2794)
			(stroke
				(width 0.1)
				(type default)
			)
			(layer "F.Fab")
		)
		(fp_line
			(start 0.67945 0.3048)
			(end 0.120396 0.3048)
			(stroke
				(width 0.1)
				(type default)
			)
			(layer "F.Fab")
		)
		(fp_line
			(start -0.12065 0.2794)
			(end -0.12065 0.3048)
			(stroke
				(width 0.1)
				(type default)
			)
			(layer "F.Fab")
		)
		(fp_line
			(start 0.120396 0.2794)
			(end -0.12065 0.2794)
			(stroke
				(width 0.1)
				(type default)
			)
			(layer "F.Fab")
		)
		(fp_line
			(start -0.12065 -0.2794)
			(end 0.12065 -0.2794)
			(stroke
				(width 0.1)
				(type default)
			)
			(layer "F.Fab")
		)
		(fp_line
			(start 0.12065 -0.2794)
			(end 0.12065 -0.3048)
			(stroke
				(width 0.1)
				(type default)
			)
			(layer "F.Fab")
		)
		(fp_line
			(start 0.12065 -0.3048)
			(end 0.67945 -0.3048)
			(stroke
				(width 0.1)
				(type default)
			)
			(layer "F.Fab")
		)
		(fp_line
			(start 0.67945 -0.3048)
			(end 0.67945 0.3048)
			(stroke
				(width 0.1)
				(type default)
			)
			(layer "F.Fab")
		)
		(fp_line
			(start -0.67945 -0.305054)
			(end -0.12065 -0.305054)
			(stroke
				(width 0.1)
				(type default)
			)
			(layer "F.Fab")
		)
		(fp_line
			(start -0.12065 -0.305054)
			(end -0.12065 -0.2794)
			(stroke
				(width 0.1)
				(type default)
			)
			(layer "F.Fab")
		)
		(pad "1" smd rect
			(at -0.40005 0 90)
			(size 0.4572 0.508)
			(layers "F.Cu" "F.Mask" "F.Paste")
			(net "USB2_HOST_BMC_B_BUF_DP")
		)
		(pad "2" smd rect
			(at 0.40005 0 90)
			(size 0.4572 0.508)
			(layers "F.Cu" "F.Mask" "F.Paste")
			(net "USB2_HUB_BUF_SWB_R_DP")
		)
	)
)
